M48
;DRILL file {KiCad (5.0.1)-3} date 10/04/2019 15:36:23
;FORMAT={-:-/ absolute / metric / decimal}
FMAT,2
METRIC,TZ
T1C1.800
T2C1.850
T3C4.000
T4C5.700
%
G90
G05
M71
T1
X25.701Y78.998
X25.701Y74.798
X25.701Y70.598
X25.701Y66.398
X29.901Y78.998
X29.901Y74.798
X29.901Y70.598
X29.901Y66.398
X6.101Y78.998
X6.101Y74.798
X6.101Y70.598
X6.101Y66.398
X10.301Y78.998
X10.301Y74.798
X10.301Y70.598
X10.301Y66.398
T2
X25.901Y48.798
X25.901Y44.598
X25.901Y40.398
X30.101Y48.798
X30.101Y44.598
X30.101Y40.398
X5.901Y19.966
X5.901Y15.766
X5.901Y11.566
X10.101Y19.966
X10.101Y15.766
X10.101Y11.566
X25.901Y19.966
X25.901Y15.766
X25.901Y11.566
X30.101Y19.966
X30.101Y15.766
X30.101Y11.566
X5.901Y48.798
X5.901Y44.598
X5.901Y40.398
X10.101Y48.798
X10.101Y44.598
X10.101Y40.398
T3
X140.001Y-0.002
X140.001Y89.998
X0.001Y89.998
X0.001Y-0.002
T4
X55.001Y32.998
X55.001Y10.498
X115.001Y80.748
X55.001Y77.998
X115.001Y58.248
X55.001Y55.498
X115.001Y13.248
X115.001Y35.748
T0
M30
